FILE_TYPE = CONNECTIVITY;
{Allegro Design Entry HDL 16.6-p007 (v16-6-112F) 10/10/2012}
"PAGE_NUMBER" = 248;
0"NC";
1"GND\g";
2"P3V3\g";
3"GND\g";
4"GND\g";
5"GND\g";
6"P3V3_STBY\g";
7"P3V3_STBY\g";
8"PVCCIO_CPU0\g";
9"PVCCIO_CPU0\g";
10"GND\g";
11"P3V3\g";
12"SMB_PEHPCPU0_STBY_LVC3_SDA";
13"SMB_CPU0_PE_HP_GTL_SCL";
14"RST_PCIE_M2_DEV_IC_N";
15"SMB_PEHPCPU0_STBY_LVC3_SCL";
16"SMB_PEHPCPU0_STBY_LVC3_R_SDA";
17"SMB_PEHPCPU0_STBY_LVC3_R_SCL";
18"TP_SMB_PEHPCPU0_EN";
19"SMB_CPU0_PE_HP_GTL_R_SDA";
20"SMB_CPU0_PE_HP_GTL_R_SCL";
21"SMB_CPU0_PE_HP_GTL_SDA";
22"RST_PCIE_M2_DEV_AND";
23"RST_PCIE_M2_DEV_N";
24"PWRGD_P12V_HSC_DLY";
25"PWRGD_P3V3";
%"TTL1G08"
"1","(-3175,1625)","0","mstr_ttl","I11";
;
CDS_SEC"1"
CDS_LOCATION"U14E2"
LOCATION"U14E2"
MATERIAL"IC"
PACK_TYPE"SOTLF"
PART_NUMBER"D10321-001"
POWER_GROUP"VCC=P3V3;GND=GND;"
VALUE"NC7SZ08"
ROOM"MIO_CHASSIS"
BOM_COST"MIO_CHASSIS"
CDS_LIB"mstr_ttl"
SEC"1"
SEC_TYPE"SOTLF";
"Y <SIZE-1..0>"
$PN"4"14;
"B <SIZE-1..0>"
$PN"2"22;
"A <SIZE-1..0>"
$PN"1"23;
%"CAP_A"
"1","(-2750,2025)","0","dev_discrete","I13";
;
MATERIAL"X7R"
TOLERANCE"10%"
VOLTAGE"16V"
LOCATION"C14W1"
PART_NUMBER"A36096-030"
VALUE"0.1UF"
PACK_TYPE"0402V"
CDS_LIB"dev_discrete"
CDS_SEC"1"
ROOM"CPUFANS"
SEC"1"
SEC_TYPE"0402V"
BOM_COST"SM_THERM"
CDS_LOCATION"C14W1";
"B"
$PN"2"1;
"A"
$PN"1"2;
%"GND"
"1","(-2750,1825)","0","mstr_symbols","I15";
;
VOLTAGE"0.0V"
CDS_LIB"mstr_symbols"
SIZE"1B"
BODY_TYPE"PLUMBING"
HDL_POWER"GND";
"A\NAC"1;
%"P3V3"
"1","(-2750,2225)","0","mstr_symbols","I16";
;
VOLTAGE"3.3V"
SIZE"1B"
BODY_TYPE"PLUMBING"
HDL_POWER"P3V3"
CDS_LIB"mstr_symbols";
"G\NAC"2;
%"CAP_A"
"1","(-3700,1175)","0","dev_discrete","I17";
;
VALUE"0.1UF"
TOLERANCE"10%"
PART_NUMBER"A36096-030"
PACK_TYPE"0402V"
VOLTAGE"16V"
MATERIAL"X7R"
LOCATION"C14W2"
BOM_COST"SM_THERM"
SEC_TYPE"0402V"
SEC"1"
ROOM"CPUFANS"
CDS_SEC"1"
CDS_LIB"dev_discrete"
CDS_LOCATION"C14W2";
"B"
$PN"2"3;
"A"
$PN"1"11;
%"GND"
"1","(-3700,975)","0","mstr_symbols","I18";
;
HDL_POWER"GND"
BODY_TYPE"PLUMBING"
SIZE"1B"
CDS_LIB"mstr_symbols"
VOLTAGE"0.0V";
"A\NAC"3;
%"TTL1G08"
"1","(-4050,1275)","0","mstr_ttl","I19";
;
CDS_SEC"1"
$SEC"1"
CDS_LOCATION"U14E3"
MATERIAL"IC"
PACK_TYPE"SOTLF"
PART_NUMBER"D10321-001"
LOCATION"U14E3"
VALUE"NC7SZ08"
POWER_GROUP"VCC=P3V3;GND=GND;"
CDS_LIB"mstr_ttl"
BOM_COST"MIO_CHASSIS"
ROOM"MIO_CHASSIS";
"Y <SIZE-1..0>"
$PN"4"22;
"B <SIZE-1..0>"
$PN"2"25;
"A <SIZE-1..0>"
$PN"1"24;
%"RES"
"1","(-6250,3525)","0","mstr_discrete","I24";
;
VALUE"10.0"
TOLERANCE"1%"
WATTAGE"1/16W"
LOCATION"R6W26"
PART_NUMBER"G21796-066"
MATERIAL"CHIP"
PACK_TYPE"0402"
CDS_LOCATION"R6W26"
SEC"1"
CDS_LIB"mstr_discrete"
SEC_TYPE"0402"
ROOM"CPU1"
CDS_SEC"1";
"B"
$PN"2"20;
"A"
$PN"1"13;
%"RES"
"1","(-5900,3475)","0","mstr_discrete","I25";
;
PART_NUMBER"G21796-066"
WATTAGE"1/16W"
LOCATION"R6W27"
TOLERANCE"1%"
VALUE"10.0"
MATERIAL"CHIP"
PACK_TYPE"0402"
SEC"1"
CDS_LIB"mstr_discrete"
SEC_TYPE"0402"
ROOM"CPU1"
CDS_SEC"1"
CDS_LOCATION"R6W27";
"B"
$PN"2"19;
"A"
$PN"1"21;
%"RES"
"2","(-4750,3875)","2","mstr_discrete","I26";
;
LOCATION"R9W19"
VALUE"240"
TOLERANCE"1.0%"
WATTAGE"1/16W"
MATERIAL"CHIP"
PART_NUMBER"G21796-294"
PACK_TYPE"0402"
CDS_LOCATION"R9W19"
CDS_SEC"1"
ROOM"SMB_PE_HP_CPU1"
SEC_TYPE"0402"
CDS_LIB"mstr_discrete"
SEC"1";
"A"
$PN"1"9;
"B"
$PN"2"20;
%"RES"
"2","(-4600,3875)","0","mstr_discrete","I27";
;
LOCATION"R9W18"
VALUE"240"
TOLERANCE"1.0%"
PART_NUMBER"G21796-294"
MATERIAL"CHIP"
WATTAGE"1/16W"
PACK_TYPE"0402"
SEC"1"
CDS_LIB"mstr_discrete"
SEC_TYPE"0402"
ROOM"SMB_PE_HP_CPU1"
CDS_SEC"1"
CDS_LOCATION"R9W18";
"A"
$PN"1"9;
"B"
$PN"2"19;
%"GND"
"1","(-4200,3825)","0","mstr_symbols","I29";
;
HDL_POWER"GND"
BODY_TYPE"PLUMBING"
VOLTAGE"0"
CDS_LIB"mstr_symbols"
SIZE"1B"
BOM_COST"NT_BASE_VRD"
ROOM"P2V5_LAN_AUX_VR";
"A\NAC"4;
%"CAP_A"
"1","(-4200,4050)","0","dev_discrete","I30";
;
LOCATION"C9W8"
PACK_TYPE"0402V"
TOLERANCE"10%"
MATERIAL"X7R"
PART_NUMBER"A36096-030"
VOLTAGE"16V"
VALUE"0.1UF"
CDS_LIB"dev_discrete"
SEC"1"
SEC_TYPE"0402V"
ROOM"SMB_PE_HP_CPU1"
CDS_SEC"1"
CDS_LOCATION"C9W8";
"B"
$PN"2"4;
"A"
$PN"1"8;
%"GND"
"1","(-3525,3825)","0","mstr_symbols","I31";
;
ROOM"P2V5_LAN_AUX_VR"
BOM_COST"NT_BASE_VRD"
SIZE"1B"
VOLTAGE"0"
BODY_TYPE"PLUMBING"
HDL_POWER"GND"
CDS_LIB"mstr_symbols";
"A\NAC"5;
%"CAP_A"
"1","(-3525,4050)","2","dev_discrete","I32";
;
LOCATION"C9W7"
VALUE"0.1UF"
VOLTAGE"16V"
TOLERANCE"10%"
MATERIAL"X7R"
PACK_TYPE"0402V"
PART_NUMBER"A36096-030"
SEC_TYPE"0402V"
SEC"1"
CDS_LIB"dev_discrete"
ROOM"SMB_PE_HP_CPU1"
CDS_SEC"1"
CDS_LOCATION"C9W7";
"B"
$PN"2"5;
"A"
$PN"1"7;
%"RES"
"2","(-2850,3875)","0","mstr_discrete","I34";
;
VALUE"2.0K"
LOCATION"R9W16"
WATTAGE"1/16W"
TOLERANCE"1%"
MATERIAL"CHIP"
PACK_TYPE"0402"
PART_NUMBER"G21796-001"
SEC"1"
CDS_LIB"mstr_discrete"
SEC_TYPE"0402"
ROOM"SMB_PE_HP_CPU1"
CDS_SEC"1"
CDS_LOCATION"R9W16";
"A"
$PN"1"6;
"B"
$PN"2"16;
%"RES"
"2","(-3000,3875)","2","mstr_discrete","I35";
;
VALUE"2.0K"
TOLERANCE"1%"
PACK_TYPE"0402"
MATERIAL"CHIP"
WATTAGE"1/16W"
LOCATION"R9W17"
PART_NUMBER"G21796-001"
SEC"1"
SEC_TYPE"0402"
CDS_LIB"mstr_discrete"
ROOM"SMB_PE_HP_CPU1"
CDS_SEC"1"
CDS_LOCATION"R9W17";
"A"
$PN"1"6;
"B"
$PN"2"17;
%"P3V3_STBY"
"1","(-2925,4275)","0","mstr_symbols","I36";
;
CDS_LIB"mstr_symbols"
SIZE"1B"
VOLTAGE"3.3V"
BODY_TYPE"PLUMBING"
HDL_POWER"P3V3_STBY";
"G\NAC"6;
%"RES"
"1","(-2450,3525)","0","mstr_discrete","I37";
;
CDS_SEC"1"
LOCATION"R9W14"
MATERIAL"CHIP"
PACK_TYPE"0402"
TOLERANCE"1%"
WATTAGE"1/16W"
VALUE"20.0"
PART_NUMBER"G21796-173"
CDS_LIB"mstr_discrete"
ROOM"SMB_PE_HP_CPU1"
CDS_LOCATION"R9W14"
SEC"1"
SEC_TYPE"0402";
"B"
$PN"2"15;
"A"
$PN"1"17;
%"RES"
"1","(-2200,3475)","0","mstr_discrete","I38";
;
CDS_SEC"1"
PACK_TYPE"0402"
VALUE"20.0"
TOLERANCE"1%"
MATERIAL"CHIP"
WATTAGE"1/16W"
PART_NUMBER"G21796-173"
LOCATION"R9W13"
CDS_LOCATION"R9W13"
CDS_LIB"mstr_discrete"
SEC_TYPE"0402"
SEC"1"
ROOM"SMB_PE_HP_CPU1";
"B"
$PN"2"12;
"A"
$PN"1"16;
%"P3V3_STBY"
"1","(-3450,4375)","0","mstr_symbols","I40";
;
HDL_POWER"P3V3_STBY"
BODY_TYPE"PLUMBING"
VOLTAGE"3.3V"
CDS_LIB"mstr_symbols"
SIZE"1B";
"G\NAC"7;
%"PVCCIO_CPU0"
"1","(-4275,4375)","0","mstr_symbols","I47";
;
CDS_LIB"mstr_symbols"
VOLTAGE"1.1V"
BODY_TYPE"PLUMBING"
HDL_POWER"PVCCIO_CPU0";
"G\NAC"8;
%"PVCCIO_CPU0"
"1","(-4700,4250)","0","mstr_symbols","I48";
;
CDS_LIB"mstr_symbols"
VOLTAGE"1.1V"
BODY_TYPE"PLUMBING"
HDL_POWER"PVCCIO_CPU0";
"G\NAC"9;
%"TCA9517DGKR-GP"
"1","(-3925,3500)","0","w_hdl","I49";
;
CDS_SEC"1"
CDS_LOCATION"U1W2"
VALUE"TCA9517DGKR-GP"
LOCATION"U1W2"
CDS_LMAN_SYM_OUTLINE"-175,175,175,-175"
CDS_LIB"w_hdl"
PART_NUMBER"071.09517.0009"
SEC_TYPE"DISCRET-G8"
SEC"1"
PACK_TYPE"DISCRET-G8";
"EN"
$PN"5"18;
"SDAB"
$PN"6"16;
"SCLB"
$PN"7"17;
"VCCB"
$PN"8"7;
"GND"
$PN"4"10;
"SDAA"
$PN"3"19;
"SCLA"
$PN"2"20;
"VCCA"
$PN"1"8;
%"GND"
"1","(-4300,3325)","0","mstr_symbols","I50";
;
CDS_LIB"mstr_symbols"
HDL_POWER"GND"
BODY_TYPE"PLUMBING"
VOLTAGE"0"
SIZE"1B"
BOM_COST"NT_BASE_VRD"
ROOM"P2V5_LAN_AUX_VR";
"A\NAC"10;
%"P3V3"
"1","(-3700,1375)","0","mstr_symbols","I9";
;
CDS_LIB"mstr_symbols"
HDL_POWER"P3V3"
BODY_TYPE"PLUMBING"
SIZE"1B"
VOLTAGE"3.3V";
"G\NAC"11;
END.
